(kicad_pcb
	(version 20240108)
	(generator "pcbnew")
	(generator_version "8.0")
	(general
		(thickness 1.62)
		(legacy_teardrops no)
	)
	(paper "A4")
	(title_block
		(title "Jetson Orin Baseboard")
		(date "2025-03-12")
		(rev "1.3.4")
		(company "Antmicro Ltd")
		(comment 1 "www.antmicro.com")
		(comment 9 "footprints 6-9 of 677")
	)
	(layers
		(0 "F.Cu" signal)
		(1 "In1.Cu" signal)
		(2 "In2.Cu" signal)
		(3 "In3.Cu" signal)
		(4 "In4.Cu" jumper)
		(5 "In5.Cu" signal)
		(6 "In6.Cu" signal)
		(31 "B.Cu" signal)
		(32 "B.Adhes" user "B.Adhesive")
		(33 "F.Adhes" user "F.Adhesive")
		(34 "B.Paste" user)
		(35 "F.Paste" user)
		(36 "B.SilkS" user "B.Silkscreen")
		(37 "F.SilkS" user "F.Silkscreen")
		(38 "B.Mask" user)
		(39 "F.Mask" user)
		(40 "Dwgs.User" user "User.Drawings")
		(41 "Cmts.User" user "User.Comments")
		(42 "Eco1.User" user "User.Eco1")
		(43 "Eco2.User" user "User.Eco2")
		(44 "Edge.Cuts" user)
		(45 "Margin" user)
		(46 "B.CrtYd" user "B.Courtyard")
		(47 "F.CrtYd" user "F.Courtyard")
		(48 "B.Fab" user)
		(49 "F.Fab" user)
	)
	(footprint "antmicro-footprints:R_0402_1005Metric"
		(layer "F.Cu")
		(at 134.7 121.1 90)
		(descr "Resistor SMD 0402")
		(tags "resistor SMD 0402")
		(property "Reference" "R223"
			(at 0.75 0.45 90)
			(layer "F.SilkS")
			(effects
				(font
					(size 0.7 0.7)
					(thickness 0.15)
				)
				(justify left bottom)
			)
		)
		(property "Value" "R_200R_0402"
			(at 0 1.4 90)
			(layer "F.Fab")
			(effects
				(font
					(size 0.7 0.7)
					(thickness 0.15)
				)
				(justify left bottom)
			)
		)
		(property "Footprint" "antmicro-footprints:R_0402_1005Metric"
			(at 0 0 90)
			(layer "F.Fab")
			(hide yes)
			(effects
				(font
					(size 1.27 1.27)
					(thickness 0.15)
				)
			)
		)
		(property "Datasheet" "https://www.bourns.com/docs/product-datasheets/cr.pdf"
			(at 0 0 90)
			(layer "F.Fab")
			(hide yes)
			(effects
				(font
					(size 1.27 1.27)
					(thickness 0.15)
				)
			)
		)
		(property "Author" "Antmicro"
			(at 255.8 -13.6 0)
			(layer "F.Fab")
			(hide yes)
			(effects
				(font
					(size 1 1)
					(thickness 0.15)
				)
			)
		)
		(property "License" "Apache-2.0"
			(at 255.8 -13.6 0)
			(layer "F.Fab")
			(hide yes)
			(effects
				(font
					(size 1 1)
					(thickness 0.15)
				)
			)
		)
		(property "MPN" "CR0402-FX-2000GLF"
			(at 255.8 -13.6 0)
			(layer "F.Fab")
			(hide yes)
			(effects
				(font
					(size 1 1)
					(thickness 0.15)
				)
			)
		)
		(property "Manufacturer" "Bourns"
			(at 255.8 -13.6 0)
			(layer "F.Fab")
			(hide yes)
			(effects
				(font
					(size 1 1)
					(thickness 0.15)
				)
			)
		)
		(property "Tolerance" "1%"
			(at 255.8 -13.6 0)
			(layer "F.Fab")
			(hide yes)
			(effects
				(font
					(size 1 1)
					(thickness 0.15)
				)
			)
		)
		(property "Val" "200R"
			(at 255.8 -13.6 0)
			(layer "F.Fab")
			(hide yes)
			(effects
				(font
					(size 1 1)
					(thickness 0.15)
				)
			)
		)
		(sheetname "Peripherals")
		(sheetfile "peripherals.kicad_sch")
		(attr smd)
		(fp_rect
			(start -0.925 -0.47)
			(end 0.925 0.47)
			(stroke
				(width 0.05)
				(type default)
			)
			(fill none)
			(layer "F.CrtYd")
		)
		(fp_rect
			(start -0.5 -0.25)
			(end 0.5 0.25)
			(stroke
				(width 0.15)
				(type solid)
			)
			(fill none)
			(layer "F.Fab")
		)
		(fp_text user "License: Apache-2.0"
			(at -0.95 5.169 90)
			(layer "F.Fab")
			(hide yes)
			(effects
				(font
					(size 0.7 0.7)
					(thickness 0.15)
				)
				(justify left bottom)
			)
		)
		(fp_text user "Author: Antmicro"
			(at -0.95 4.169 90)
			(layer "F.Fab")
			(hide yes)
			(effects
				(font
					(size 0.7 0.7)
					(thickness 0.15)
				)
				(justify left bottom)
			)
		)
		(fp_text user "${REFERENCE}"
			(at -0.95 3.168 90)
			(layer "F.Fab")
			(hide yes)
			(effects
				(font
					(size 0.7 0.7)
					(thickness 0.15)
				)
				(justify left bottom)
			)
		)
		(pad "1" smd roundrect
			(at -0.48 0 90)
			(size 0.59 0.64)
			(layers "F.Cu" "F.Paste" "F.Mask")
			(roundrect_rratio 0.25)
			(net 180 "Net-(D26-A)")
			(pintype "passive")
		)
		(pad "2" smd roundrect
			(at 0.48 0 90)
			(size 0.59 0.64)
			(layers "F.Cu" "F.Paste" "F.Mask")
			(roundrect_rratio 0.25)
			(net 87 "+3V3")
			(pintype "passive")
		)
	)
	(footprint "antmicro-footprints:R_0603_1608Metric"
		(layer "F.Cu")
		(at 137.2 110.3)
		(descr "Resistor SMD 0603")
		(tags "resistor SMD 0603")
		(property "Reference" "R233"
			(at -3.94 0.43 0)
			(layer "F.SilkS")
			(effects
				(font
					(size 0.7 0.7)
					(thickness 0.15)
				)
				(justify left bottom)
			)
		)
		(property "Value" "R_0R_22.4A_0603"
			(at 0 1.6 0)
			(layer "F.Fab")
			(effects
				(font
					(size 0.7 0.7)
					(thickness 0.15)
				)
				(justify left bottom)
			)
		)
		(property "Footprint" "antmicro-footprints:R_0603_1608Metric"
			(at 0 0 0)
			(layer "F.Fab")
			(hide yes)
			(effects
				(font
					(size 1.27 1.27)
					(thickness 0.15)
				)
			)
		)
		(property "Datasheet" "https://fscdn.rohm.com/en/products/databook/datasheet/passive/resistor/chip_resistor/pmr-jpw-e.pdf"
			(at 0 0 0)
			(layer "F.Fab")
			(hide yes)
			(effects
				(font
					(size 1.27 1.27)
					(thickness 0.15)
				)
			)
		)
		(property "Author" "Antmicro"
			(at 0 0 0)
			(layer "F.Fab")
			(hide yes)
			(effects
				(font
					(size 1 1)
					(thickness 0.15)
				)
			)
		)
		(property "License" "Apache-2.0"
			(at 0 0 0)
			(layer "F.Fab")
			(hide yes)
			(effects
				(font
					(size 1 1)
					(thickness 0.15)
				)
			)
		)
		(property "MPN" "PMR03EZPJ000"
			(at 0 0 0)
			(layer "F.Fab")
			(hide yes)
			(effects
				(font
					(size 1 1)
					(thickness 0.15)
				)
			)
		)
		(property "Manufacturer" "ROHM Semiconductor"
			(at 0 0 0)
			(layer "F.Fab")
			(hide yes)
			(effects
				(font
					(size 1 1)
					(thickness 0.15)
				)
			)
		)
		(property "Max. Curr." "22.4A"
			(at 0 0 0)
			(layer "F.Fab")
			(hide yes)
			(effects
				(font
					(size 1 1)
					(thickness 0.15)
				)
			)
		)
		(property "Tolerance" "template_tolerance"
			(at 0 0 0)
			(layer "F.Fab")
			(hide yes)
			(effects
				(font
					(size 1 1)
					(thickness 0.15)
				)
			)
		)
		(property "Val" "0R"
			(at 0 0 0)
			(layer "F.Fab")
			(hide yes)
			(effects
				(font
					(size 1 1)
					(thickness 0.15)
				)
			)
		)
		(sheetname "Peripherals")
		(sheetfile "peripherals.kicad_sch")
		(attr smd)
		(fp_line
			(start -0.15 -0.4)
			(end 0.15 -0.4)
			(stroke
				(width 0.15)
				(type solid)
			)
			(layer "F.SilkS")
		)
		(fp_line
			(start -0.15 0.4)
			(end 0.15 0.4)
			(stroke
				(width 0.15)
				(type solid)
			)
			(layer "F.SilkS")
		)
		(fp_rect
			(start -1.25 -0.65)
			(end 1.25 0.65)
			(stroke
				(width 0.05)
				(type solid)
			)
			(fill none)
			(layer "F.CrtYd")
		)
		(fp_rect
			(start -0.8 -0.4)
			(end 0.8 0.4)
			(stroke
				(width 0.15)
				(type solid)
			)
			(fill none)
			(layer "F.Fab")
		)
		(fp_text user "${REFERENCE}"
			(at -1.25 3.898 0)
			(layer "F.Fab")
			(hide yes)
			(effects
				(font
					(size 0.7 0.7)
					(thickness 0.15)
				)
				(justify left bottom)
			)
		)
		(fp_text user "Author: Antmicro"
			(at -1.25 4.9 0)
			(layer "F.Fab")
			(hide yes)
			(effects
				(font
					(size 0.7 0.7)
					(thickness 0.15)
				)
				(justify left bottom)
			)
		)
		(fp_text user "License: Apache-2.0"
			(at -1.25 5.9 0)
			(layer "F.Fab")
			(hide yes)
			(effects
				(font
					(size 0.7 0.7)
					(thickness 0.15)
				)
				(justify left bottom)
			)
		)
		(pad "1" smd roundrect
			(at -0.7 0)
			(size 0.8 1)
			(layers "F.Cu" "F.Paste" "F.Mask")
			(roundrect_rratio 0.2)
			(net 87 "+3V3")
			(pintype "passive")
		)
		(pad "2" smd roundrect
			(at 0.7 0)
			(size 0.8 1)
			(layers "F.Cu" "F.Paste" "F.Mask")
			(roundrect_rratio 0.2)
			(net 482 "/Peripherals/3V3_CONN")
			(pintype "passive")
		)
	)
	(footprint "antmicro-footprints:C_0402_1005Metric"
		(layer "F.Cu")
		(at 68.6 119 -90)
		(descr "Capacitor SMD 0402")
		(tags "capacitor SMD 0402")
		(property "Reference" "C57"
			(at 1.2 -1.28 -90)
			(layer "F.SilkS")
			(effects
				(font
					(size 0.7 0.7)
					(thickness 0.15)
				)
				(justify left bottom)
			)
		)
		(property "Value" "C_100n_0402"
			(at 0 1.4 -90)
			(layer "F.Fab")
			(effects
				(font
					(size 0.7 0.7)
					(thickness 0.15)
				)
				(justify left bottom)
			)
		)
		(property "Footprint" "antmicro-footprints:C_0402_1005Metric"
			(at 0 0 -90)
			(layer "F.Fab")
			(hide yes)
			(effects
				(font
					(size 1.27 1.27)
					(thickness 0.15)
				)
			)
		)
		(property "Datasheet" "https://www.murata.com/products/productdetail?partno=GRM155R61H104KE14%23"
			(at 0 0 -90)
			(layer "F.Fab")
			(hide yes)
			(effects
				(font
					(size 1.27 1.27)
					(thickness 0.15)
				)
			)
		)
		(property "Author" "Antmicro"
			(at -50.4 187.6 0)
			(layer "F.Fab")
			(hide yes)
			(effects
				(font
					(size 1 1)
					(thickness 0.15)
				)
			)
		)
		(property "Dielectric" "X5R"
			(at -50.4 187.6 0)
			(layer "F.Fab")
			(hide yes)
			(effects
				(font
					(size 1 1)
					(thickness 0.15)
				)
			)
		)
		(property "License" "Apache-2.0"
			(at -50.4 187.6 0)
			(layer "F.Fab")
			(hide yes)
			(effects
				(font
					(size 1 1)
					(thickness 0.15)
				)
			)
		)
		(property "MPN" "GRM155R61H104KE14D"
			(at -50.4 187.6 0)
			(layer "F.Fab")
			(hide yes)
			(effects
				(font
					(size 1 1)
					(thickness 0.15)
				)
			)
		)
		(property "Manufacturer" "Murata"
			(at -50.4 187.6 0)
			(layer "F.Fab")
			(hide yes)
			(effects
				(font
					(size 1 1)
					(thickness 0.15)
				)
			)
		)
		(property "Val" "100n"
			(at -50.4 187.6 0)
			(layer "F.Fab")
			(hide yes)
			(effects
				(font
					(size 1 1)
					(thickness 0.15)
				)
			)
		)
		(property "Voltage" "50V"
			(at -50.4 187.6 0)
			(layer "F.Fab")
			(hide yes)
			(effects
				(font
					(size 1 1)
					(thickness 0.15)
				)
			)
		)
		(sheetname "USB Debug, DP")
		(sheetfile "usb.kicad_sch")
		(attr smd)
		(fp_rect
			(start -0.925 -0.47)
			(end 0.925 0.47)
			(stroke
				(width 0.05)
				(type default)
			)
			(fill none)
			(layer "F.CrtYd")
		)
		(fp_line
			(start -0.494 0.248)
			(end -0.494 -0.25)
			(stroke
				(width 0.15)
				(type solid)
			)
			(layer "F.Fab")
		)
		(fp_line
			(start 0.504 0.248)
			(end -0.494 0.248)
			(stroke
				(width 0.15)
				(type solid)
			)
			(layer "F.Fab")
		)
		(fp_line
			(start -0.494 -0.25)
			(end 0.504 -0.25)
			(stroke
				(width 0.15)
				(type solid)
			)
			(layer "F.Fab")
		)
		(fp_line
			(start 0.504 -0.25)
			(end 0.504 0.248)
			(stroke
				(width 0.15)
				(type solid)
			)
			(layer "F.Fab")
		)
		(fp_text user "${REFERENCE}"
			(at -0.932 3.168 -90)
			(layer "F.Fab")
			(hide yes)
			(effects
				(font
					(size 0.7 0.7)
					(thickness 0.15)
				)
				(justify left bottom)
			)
		)
		(fp_text user "Author: Antmicro"
			(at -0.932 4.17 -90)
			(layer "F.Fab")
			(hide yes)
			(effects
				(font
					(size 0.7 0.7)
					(thickness 0.15)
				)
				(justify left bottom)
			)
		)
		(fp_text user "License: Apache-2.0"
			(at -0.932 5.17 -90)
			(layer "F.Fab")
			(hide yes)
			(effects
				(font
					(size 0.7 0.7)
					(thickness 0.15)
				)
				(justify left bottom)
			)
		)
		(pad "1" smd roundrect
			(at -0.48 0 270)
			(size 0.59 0.64)
			(layers "F.Cu" "F.Paste" "F.Mask")
			(roundrect_rratio 0.25)
			(net 99 "+5V")
			(pintype "passive")
		)
		(pad "2" smd roundrect
			(at 0.48 0 270)
			(size 0.59 0.64)
			(layers "F.Cu" "F.Paste" "F.Mask")
			(roundrect_rratio 0.25)
			(net 1 "GND")
			(pintype "passive")
		)
	)
	(footprint "antmicro-footprints:R_0603_1608Metric"
		(layer "F.Cu")
		(at 137.2 114.4 180)
		(descr "Resistor SMD 0603")
		(tags "resistor SMD 0603")
		(property "Reference" "R235"
			(at 1.15 -0.5 0)
			(layer "F.SilkS")
			(effects
				(font
					(size 0.7 0.7)
					(thickness 0.15)
				)
				(justify right bottom)
			)
		)
		(property "Value" "R_0R_22.4A_0603"
			(at 0 1.6 0)
			(layer "F.Fab")
			(effects
				(font
					(size 0.7 0.7)
					(thickness 0.15)
				)
				(justify right bottom)
			)
		)
		(property "Footprint" "antmicro-footprints:R_0603_1608Metric"
			(at 0 0 180)
			(layer "F.Fab")
			(hide yes)
			(effects
				(font
					(size 1.27 1.27)
					(thickness 0.15)
				)
			)
		)
		(property "Datasheet" "https://fscdn.rohm.com/en/products/databook/datasheet/passive/resistor/chip_resistor/pmr-jpw-e.pdf"
			(at 0 0 180)
			(layer "F.Fab")
			(hide yes)
			(effects
				(font
					(size 1.27 1.27)
					(thickness 0.15)
				)
			)
		)
		(property "Author" "Antmicro"
			(at 274.4 228.8 0)
			(layer "F.Fab")
			(hide yes)
			(effects
				(font
					(size 1 1)
					(thickness 0.15)
				)
			)
		)
		(property "License" "Apache-2.0"
			(at 274.4 228.8 0)
			(layer "F.Fab")
			(hide yes)
			(effects
				(font
					(size 1 1)
					(thickness 0.15)
				)
			)
		)
		(property "MPN" "PMR03EZPJ000"
			(at 274.4 228.8 0)
			(layer "F.Fab")
			(hide yes)
			(effects
				(font
					(size 1 1)
					(thickness 0.15)
				)
			)
		)
		(property "Manufacturer" "ROHM Semiconductor"
			(at 274.4 228.8 0)
			(layer "F.Fab")
			(hide yes)
			(effects
				(font
					(size 1 1)
					(thickness 0.15)
				)
			)
		)
		(property "Max. Curr." "22.4A"
			(at 274.4 228.8 0)
			(layer "F.Fab")
			(hide yes)
			(effects
				(font
					(size 1 1)
					(thickness 0.15)
				)
			)
		)
		(property "Tolerance" "template_tolerance"
			(at 274.4 228.8 0)
			(layer "F.Fab")
			(hide yes)
			(effects
				(font
					(size 1 1)
					(thickness 0.15)
				)
			)
		)
		(property "Val" "0R"
			(at 274.4 228.8 0)
			(layer "F.Fab")
			(hide yes)
			(effects
				(font
					(size 1 1)
					(thickness 0.15)
				)
			)
		)
		(sheetname "Peripherals")
		(sheetfile "peripherals.kicad_sch")
		(attr smd)
		(fp_line
			(start -0.15 0.4)
			(end 0.15 0.4)
			(stroke
				(width 0.15)
				(type solid)
			)
			(layer "F.SilkS")
		)
		(fp_line
			(start -0.15 -0.4)
			(end 0.15 -0.4)
			(stroke
				(width 0.15)
				(type solid)
			)
			(layer "F.SilkS")
		)
		(fp_rect
			(start -1.25 -0.65)
			(end 1.25 0.65)
			(stroke
				(width 0.05)
				(type solid)
			)
			(fill none)
			(layer "F.CrtYd")
		)
		(fp_rect
			(start -0.8 -0.4)
			(end 0.8 0.4)
			(stroke
				(width 0.15)
				(type solid)
			)
			(fill none)
			(layer "F.Fab")
		)
		(fp_text user "License: Apache-2.0"
			(at -1.25 5.9 0)
			(layer "F.Fab")
			(hide yes)
			(effects
				(font
					(size 0.7 0.7)
					(thickness 0.15)
				)
				(justify right bottom)
			)
		)
		(fp_text user "Author: Antmicro"
			(at -1.25 4.9 0)
			(layer "F.Fab")
			(hide yes)
			(effects
				(font
					(size 0.7 0.7)
					(thickness 0.15)
				)
				(justify right bottom)
			)
		)
		(fp_text user "${REFERENCE}"
			(at -1.25 3.898 0)
			(layer "F.Fab")
			(hide yes)
			(effects
				(font
					(size 0.7 0.7)
					(thickness 0.15)
				)
				(justify right bottom)
			)
		)
		(pad "1" smd roundrect
			(at -0.7 0 180)
			(size 0.8 1)
			(layers "F.Cu" "F.Paste" "F.Mask")
			(roundrect_rratio 0.2)
			(net 479 "/Peripherals/5V_CONN")
			(pintype "passive")
		)
		(pad "2" smd roundrect
			(at 0.7 0 180)
			(size 0.8 1)
			(layers "F.Cu" "F.Paste" "F.Mask")
			(roundrect_rratio 0.2)
			(net 99 "+5V")
			(pintype "passive")
		)
	)
)
